(kicad_pcb
	(version 20260206)
	(generator "pcbnew")
	(generator_version "10.0")
	(general
		(thickness 1.6)
		(legacy_teardrops no)
	)
	(paper "A4")
	(title_block
		(title "03242023_DA0F0TMBIJ0_F0T_Motherboard_J_brd_V01_OCP.brd")
		(comment 1 "Grand Teton / footprints 1900-1905 of 6105")
	)
	(layers
		(0 "F.Cu" signal "TOP")
		(4 "In1.Cu" signal "GND")
		(6 "In2.Cu" signal "IN1")
		(8 "In3.Cu" signal "GND1")
		(10 "In4.Cu" signal "IN2")
		(12 "In5.Cu" signal "GND2")
		(14 "In6.Cu" signal "IN3")
		(16 "In7.Cu" signal "GND3")
		(18 "In8.Cu" signal "VCC")
		(20 "In9.Cu" signal "VCC1")
		(22 "In10.Cu" signal "GND4")
		(24 "In11.Cu" signal "IN4")
		(26 "In12.Cu" signal "GND5")
		(28 "In13.Cu" signal "IN5")
		(30 "In14.Cu" signal "GND6")
		(32 "In15.Cu" signal "IN6")
		(34 "In16.Cu" signal "GND7")
		(2 "B.Cu" signal "BOTTOM")
		(9 "F.Adhes" user "F.Adhesive")
		(11 "B.Adhes" user "B.Adhesive")
		(13 "F.Paste" user "Package Geometry/Pastemask Top")
		(15 "B.Paste" user "Package Geometry/Pastemask Bottom")
		(5 "F.SilkS" user "Ref Des/Silkscreen Top")
		(7 "B.SilkS" user "Ref Des/Silkscreen Bottom")
		(1 "F.Mask" user "Board Geometry/Soldermask Top")
		(3 "B.Mask" user "Board Geometry/Soldermask Bottom")
		(17 "Dwgs.User" user "User.Drawings")
		(19 "Cmts.User" user "User.Comments")
		(21 "Eco1.User" user "User.Eco1")
		(23 "Eco2.User" user "User.Eco2")
		(25 "Edge.Cuts" user "Board Geometry/Outline")
		(27 "Margin" user)
		(31 "F.CrtYd" user "Package Geometry/Place Bound Top")
		(29 "B.CrtYd" user "Package Geometry/Place Bound Bottom")
		(35 "F.Fab" user "Ref Des/Assembly Top")
		(33 "B.Fab" user "Ref Des/Assembly Bottom")
	)
	(footprint ""
		(layer "F.Cu")
		(at 131.65074 -112.791748 180)
		(property "Reference" "U215"
			(at -0.04572 -2.506472 0)
			(unlocked yes)
			(layer "F.SilkS")
			(effects
				(font
					(size 0.7874 0.5842)
					(thickness 0.1524)
				)
			)
		)
		(property "Value" ""
			(at 0 0 180)
			(layer "F.Fab")
			(effects
				(font
					(size 1.27 1.27)
				)
			)
		)
		(duplicate_pad_numbers_are_jumpers no)
		(fp_line
			(start 1.949958 1.610106)
			(end -1.949958 1.610106)
			(stroke
				(width 0.1524)
				(type default)
			)
			(layer "F.SilkS")
		)
		(fp_line
			(start 1.949958 -1.560068)
			(end 1.949958 1.610106)
			(stroke
				(width 0.1524)
				(type default)
			)
			(layer "F.SilkS")
		)
		(fp_line
			(start -1.949958 1.610106)
			(end -1.949958 -1.610106)
			(stroke
				(width 0.1524)
				(type default)
			)
			(layer "F.SilkS")
		)
		(fp_line
			(start -1.949958 -1.610106)
			(end 1.949958 -1.610106)
			(stroke
				(width 0.1524)
				(type default)
			)
			(layer "F.SilkS")
		)
		(fp_line
			(start 0.750062 1.560068)
			(end -0.750062 1.560068)
			(stroke
				(width 0.1)
				(type default)
			)
			(layer "F.Fab")
		)
		(fp_line
			(start 0.750062 -1.560068)
			(end 0.750062 1.560068)
			(stroke
				(width 0.1)
				(type default)
			)
			(layer "F.Fab")
		)
		(fp_line
			(start -0.750062 1.560068)
			(end -0.750062 -1.560068)
			(stroke
				(width 0.1)
				(type default)
			)
			(layer "F.Fab")
		)
		(fp_line
			(start -0.750062 -1.560068)
			(end 0.750062 -1.560068)
			(stroke
				(width 0.1)
				(type default)
			)
			(layer "F.Fab")
		)
		(pad "D" smd rect
			(at 1.100074 0 90)
			(size 1.016 1.4224)
			(layers "F.Cu" "F.Mask" "F.Paste")
			(net "HP_LVC3_OCP_V3_2_PRSNT2")
		)
		(pad "G" smd rect
			(at -1.100074 -0.94996 90)
			(size 1.016 1.4224)
			(layers "F.Cu" "F.Mask" "F.Paste")
			(net "HP_LVC3_OCP_V3_2_PRSNT2_N")
		)
		(pad "S" smd rect
			(at -1.100074 0.94996 90)
			(size 1.016 1.4224)
			(layers "F.Cu" "F.Mask" "F.Paste")
			(net "GND")
		)
	)
	(footprint ""
		(layer "F.Cu")
		(at 29.715714 -109.333538)
		(property "Reference" "U269"
			(at -3.27914 -4.806188 0)
			(unlocked yes)
			(layer "F.SilkS")
			(effects
				(font
					(size 0.7874 0.5842)
					(thickness 0.1524)
				)
				(justify left)
			)
		)
		(property "Value" ""
			(at 0 0 0)
			(layer "F.Fab")
			(effects
				(font
					(size 1.27 1.27)
				)
			)
		)
		(duplicate_pad_numbers_are_jumpers no)
		(fp_line
			(start -1.868932 -2.549906)
			(end -1.868932 2.549906)
			(stroke
				(width 0.1524)
				(type default)
			)
			(layer "F.SilkS")
		)
		(fp_line
			(start -1.868932 2.549906)
			(end 1.868932 2.549906)
			(stroke
				(width 0.1524)
				(type default)
			)
			(layer "F.SilkS")
		)
		(fp_line
			(start -1.025906 -2.549906)
			(end -1.868932 -2.549906)
			(stroke
				(width 0.1524)
				(type default)
			)
			(layer "F.SilkS")
		)
		(fp_line
			(start 0 -1.524)
			(end -1.025906 -2.549906)
			(stroke
				(width 0.1524)
				(type default)
			)
			(layer "F.SilkS")
		)
		(fp_line
			(start 1.025906 -2.549906)
			(end 0 -1.524)
			(stroke
				(width 0.1524)
				(type default)
			)
			(layer "F.SilkS")
		)
		(fp_line
			(start 1.868932 -2.549906)
			(end 1.025906 -2.549906)
			(stroke
				(width 0.1524)
				(type default)
			)
			(layer "F.SilkS")
		)
		(fp_line
			(start 1.868932 2.549906)
			(end 1.868932 -2.549906)
			(stroke
				(width 0.1524)
				(type default)
			)
			(layer "F.SilkS")
		)
		(fp_poly
			(pts
				(xy -2.227326 -3.828796) (xy -2.735326 -2.812796) (xy -3.243326 -3.828796)
			)
			(stroke
				(width 0)
				(type default)
			)
			(fill yes)
			(layer "F.SilkS")
		)
		(fp_line
			(start -2.249932 -2.549906)
			(end -2.249932 2.549906)
			(stroke
				(width 0.1)
				(type default)
			)
			(layer "F.Fab")
		)
		(fp_line
			(start -2.249932 2.549906)
			(end 2.249932 2.549906)
			(stroke
				(width 0.1)
				(type default)
			)
			(layer "F.Fab")
		)
		(fp_line
			(start 2.249932 -2.549906)
			(end -2.249932 -2.549906)
			(stroke
				(width 0.1)
				(type default)
			)
			(layer "F.Fab")
		)
		(fp_line
			(start 2.249932 2.549906)
			(end 2.249932 -2.549906)
			(stroke
				(width 0.1)
				(type default)
			)
			(layer "F.Fab")
		)
		(fp_poly
			(pts
				(xy -4.7752 -1.787398) (xy -4.7752 -2.803398) (xy -3.7592 -2.295398)
			)
			(stroke
				(width 0)
				(type default)
			)
			(fill yes)
			(layer "F.Fab")
		)
		(pad "1" smd rect
			(at -2.800096 -2.275078 270)
			(size 0.3556 1.6002)
			(layers "F.Cu" "F.Mask" "F.Paste")
			(net "ADC128_VREF")
		)
		(pad "2" smd rect
			(at -2.800096 -1.625092 270)
			(size 0.3556 1.6002)
			(layers "F.Cu" "F.Mask" "F.Paste")
			(net "SMB_SEN_TIC_3V3AUX_SDA")
		)
		(pad "3" smd rect
			(at -2.800096 -0.975106 270)
			(size 0.3556 1.6002)
			(layers "F.Cu" "F.Mask" "F.Paste")
			(net "SMB_SEN_TIC_3V3AUX_SCL")
		)
		(pad "4" smd rect
			(at -2.800096 -0.32512 270)
			(size 0.3556 1.6002)
			(layers "F.Cu" "F.Mask" "F.Paste")
			(net "GND")
		)
		(pad "5" smd rect
			(at -2.800096 0.32512 270)
			(size 0.3556 1.6002)
			(layers "F.Cu" "F.Mask" "F.Paste")
			(net "P3V3_ADC128_VCC")
		)
		(pad "6" smd rect
			(at -2.800096 0.975106 270)
			(size 0.3556 1.6002)
			(layers "F.Cu" "F.Mask" "F.Paste")
			(net "TP_ADC128_INT")
		)
		(pad "7" smd rect
			(at -2.800096 1.625092 270)
			(size 0.3556 1.6002)
			(layers "F.Cu" "F.Mask" "F.Paste")
			(net "ADC128_A0")
		)
		(pad "8" smd rect
			(at -2.800096 2.275078 270)
			(size 0.3556 1.6002)
			(layers "F.Cu" "F.Mask" "F.Paste")
			(net "ADC128_A1")
		)
		(pad "9" smd rect
			(at 2.800096 2.275078 270)
			(size 0.3556 1.6002)
			(layers "F.Cu" "F.Mask" "F.Paste")
			(net "P12V_E1S_0_ISENSE_TIC")
		)
		(pad "10" smd rect
			(at 2.800096 1.625092 270)
			(size 0.3556 1.6002)
			(layers "F.Cu" "F.Mask" "F.Paste")
			(net "P3V3_PDB_AUX_ADC_TIC")
		)
		(pad "11" smd rect
			(at 2.800096 0.975106 270)
			(size 0.3556 1.6002)
			(layers "F.Cu" "F.Mask" "F.Paste")
			(net "P3V3_AUX_ADC_TIC")
		)
		(pad "12" smd rect
			(at 2.800096 0.32512 270)
			(size 0.3556 1.6002)
			(layers "F.Cu" "F.Mask" "F.Paste")
			(net "P3V3_ADC_TIC")
		)
		(pad "13" smd rect
			(at 2.800096 -0.32512 270)
			(size 0.3556 1.6002)
			(layers "F.Cu" "F.Mask" "F.Paste")
			(net "P5V_ADC_TIC")
		)
		(pad "14" smd rect
			(at 2.800096 -0.975106 270)
			(size 0.3556 1.6002)
			(layers "F.Cu" "F.Mask" "F.Paste")
			(net "P12V_OCP_V3_2_ISENSE_TIC")
		)
		(pad "15" smd rect
			(at 2.800096 -1.625092 270)
			(size 0.3556 1.6002)
			(layers "F.Cu" "F.Mask" "F.Paste")
			(net "P12V_OCP_SFF_ISENSE_TIC")
		)
		(pad "16" smd rect
			(at 2.800096 -2.275078 270)
			(size 0.3556 1.6002)
			(layers "F.Cu" "F.Mask" "F.Paste")
			(net "P12V_AUX_ADC_TIC")
		)
	)
	(footprint ""
		(layer "F.Cu")
		(at 169.44848 -422.874948 180)
		(property "Reference" "R2916"
			(at 0 0 180)
			(layer "F.SilkS")
			(hide yes)
			(effects
				(font
					(size 1.27 1.27)
				)
			)
		)
		(property "Value" ""
			(at 0 0 180)
			(layer "F.Fab")
			(effects
				(font
					(size 1.27 1.27)
				)
			)
		)
		(duplicate_pad_numbers_are_jumpers no)
		(fp_line
			(start 0.7874 0.4064)
			(end -0.7874 0.4064)
			(stroke
				(width 0.1524)
				(type default)
			)
			(layer "F.SilkS")
		)
		(fp_line
			(start 0.7874 -0.4064)
			(end 0.7874 0.4064)
			(stroke
				(width 0.1524)
				(type default)
			)
			(layer "F.SilkS")
		)
		(fp_line
			(start -0.7874 0.4064)
			(end -0.7874 -0.4064)
			(stroke
				(width 0.1524)
				(type default)
			)
			(layer "F.SilkS")
		)
		(fp_line
			(start -0.7874 -0.4064)
			(end 0.7874 -0.4064)
			(stroke
				(width 0.1524)
				(type default)
			)
			(layer "F.SilkS")
		)
		(fp_line
			(start 0.67945 0.3048)
			(end 0.120396 0.3048)
			(stroke
				(width 0.1)
				(type default)
			)
			(layer "F.Fab")
		)
		(fp_line
			(start 0.67945 -0.3048)
			(end 0.67945 0.3048)
			(stroke
				(width 0.1)
				(type default)
			)
			(layer "F.Fab")
		)
		(fp_line
			(start 0.12065 -0.2794)
			(end 0.12065 -0.3048)
			(stroke
				(width 0.1)
				(type default)
			)
			(layer "F.Fab")
		)
		(fp_line
			(start 0.12065 -0.3048)
			(end 0.67945 -0.3048)
			(stroke
				(width 0.1)
				(type default)
			)
			(layer "F.Fab")
		)
		(fp_line
			(start 0.120396 0.3048)
			(end 0.120396 0.2794)
			(stroke
				(width 0.1)
				(type default)
			)
			(layer "F.Fab")
		)
		(fp_line
			(start 0.120396 0.2794)
			(end -0.12065 0.2794)
			(stroke
				(width 0.1)
				(type default)
			)
			(layer "F.Fab")
		)
		(fp_line
			(start -0.12065 0.3048)
			(end -0.67945 0.3048)
			(stroke
				(width 0.1)
				(type default)
			)
			(layer "F.Fab")
		)
		(fp_line
			(start -0.12065 0.2794)
			(end -0.12065 0.3048)
			(stroke
				(width 0.1)
				(type default)
			)
			(layer "F.Fab")
		)
		(fp_line
			(start -0.12065 -0.2794)
			(end 0.12065 -0.2794)
			(stroke
				(width 0.1)
				(type default)
			)
			(layer "F.Fab")
		)
		(fp_line
			(start -0.12065 -0.305054)
			(end -0.12065 -0.2794)
			(stroke
				(width 0.1)
				(type default)
			)
			(layer "F.Fab")
		)
		(fp_line
			(start -0.67945 0.3048)
			(end -0.67945 -0.305054)
			(stroke
				(width 0.1)
				(type default)
			)
			(layer "F.Fab")
		)
		(fp_line
			(start -0.67945 -0.305054)
			(end -0.12065 -0.305054)
			(stroke
				(width 0.1)
				(type default)
			)
			(layer "F.Fab")
		)
		(pad "1" smd circle
			(at -0.40005 0 180)
			(size 0 0)
			(layers "F.Cu" "F.Mask" "F.Paste")
			(net "RST_SWB_BIC_R_N")
		)
		(pad "2" smd circle
			(at 0.40005 0 180)
			(size 0 0)
			(layers "F.Cu" "F.Mask" "F.Paste")
			(net "GND")
		)
	)
	(footprint ""
		(layer "F.Cu")
		(at 180.64988 -130.266948 90)
		(property "Reference" "R1418"
			(at 0 0 90)
			(layer "F.SilkS")
			(hide yes)
			(effects
				(font
					(size 1.27 1.27)
				)
			)
		)
		(property "Value" ""
			(at 0 0 90)
			(layer "F.Fab")
			(effects
				(font
					(size 1.27 1.27)
				)
			)
		)
		(duplicate_pad_numbers_are_jumpers no)
		(fp_line
			(start 0.7874 -0.4064)
			(end 0.7874 0.4064)
			(stroke
				(width 0.1524)
				(type default)
			)
			(layer "F.SilkS")
		)
		(fp_line
			(start -0.7874 -0.4064)
			(end 0.7874 -0.4064)
			(stroke
				(width 0.1524)
				(type default)
			)
			(layer "F.SilkS")
		)
		(fp_line
			(start 0.7874 0.4064)
			(end -0.7874 0.4064)
			(stroke
				(width 0.1524)
				(type default)
			)
			(layer "F.SilkS")
		)
		(fp_line
			(start -0.7874 0.4064)
			(end -0.7874 -0.4064)
			(stroke
				(width 0.1524)
				(type default)
			)
			(layer "F.SilkS")
		)
		(fp_line
			(start -0.12065 -0.305054)
			(end -0.12065 -0.2794)
			(stroke
				(width 0.1)
				(type default)
			)
			(layer "F.Fab")
		)
		(fp_line
			(start -0.67945 -0.305054)
			(end -0.12065 -0.305054)
			(stroke
				(width 0.1)
				(type default)
			)
			(layer "F.Fab")
		)
		(fp_line
			(start 0.67945 -0.3048)
			(end 0.67945 0.3048)
			(stroke
				(width 0.1)
				(type default)
			)
			(layer "F.Fab")
		)
		(fp_line
			(start 0.12065 -0.3048)
			(end 0.67945 -0.3048)
			(stroke
				(width 0.1)
				(type default)
			)
			(layer "F.Fab")
		)
		(fp_line
			(start 0.12065 -0.2794)
			(end 0.12065 -0.3048)
			(stroke
				(width 0.1)
				(type default)
			)
			(layer "F.Fab")
		)
		(fp_line
			(start -0.12065 -0.2794)
			(end 0.12065 -0.2794)
			(stroke
				(width 0.1)
				(type default)
			)
			(layer "F.Fab")
		)
		(fp_line
			(start 0.120396 0.2794)
			(end -0.12065 0.2794)
			(stroke
				(width 0.1)
				(type default)
			)
			(layer "F.Fab")
		)
		(fp_line
			(start -0.12065 0.2794)
			(end -0.12065 0.3048)
			(stroke
				(width 0.1)
				(type default)
			)
			(layer "F.Fab")
		)
		(fp_line
			(start 0.67945 0.3048)
			(end 0.120396 0.3048)
			(stroke
				(width 0.1)
				(type default)
			)
			(layer "F.Fab")
		)
		(fp_line
			(start 0.120396 0.3048)
			(end 0.120396 0.2794)
			(stroke
				(width 0.1)
				(type default)
			)
			(layer "F.Fab")
		)
		(fp_line
			(start -0.12065 0.3048)
			(end -0.67945 0.3048)
			(stroke
				(width 0.1)
				(type default)
			)
			(layer "F.Fab")
		)
		(fp_line
			(start -0.67945 0.3048)
			(end -0.67945 -0.305054)
			(stroke
				(width 0.1)
				(type default)
			)
			(layer "F.Fab")
		)
		(pad "1" smd circle
			(at -0.40005 0 90)
			(size 0 0)
			(layers "F.Cu" "F.Mask" "F.Paste")
			(net "RST_PCIE_CPU1_DEV_PERST_N")
		)
		(pad "2" smd circle
			(at 0.40005 0 90)
			(size 0 0)
			(layers "F.Cu" "F.Mask" "F.Paste")
			(net "GND")
		)
	)
	(footprint ""
		(layer "F.Cu")
		(at 367.44783 -255.053846 90)
		(property "Reference" "C1012"
			(at 0 0 90)
			(layer "F.SilkS")
			(hide yes)
			(effects
				(font
					(size 1.27 1.27)
				)
			)
		)
		(property "Value" ""
			(at 0 0 90)
			(layer "F.Fab")
			(effects
				(font
					(size 1.27 1.27)
				)
			)
		)
		(duplicate_pad_numbers_are_jumpers no)
		(fp_line
			(start 0.7874 -0.4064)
			(end 0.7874 0.4064)
			(stroke
				(width 0.1524)
				(type default)
			)
			(layer "F.SilkS")
		)
		(fp_line
			(start -0.7874 -0.4064)
			(end 0.7874 -0.4064)
			(stroke
				(width 0.1524)
				(type default)
			)
			(layer "F.SilkS")
		)
		(fp_line
			(start 0.7874 0.4064)
			(end -0.7874 0.4064)
			(stroke
				(width 0.1524)
				(type default)
			)
			(layer "F.SilkS")
		)
		(fp_line
			(start -0.7874 0.4064)
			(end -0.7874 -0.4064)
			(stroke
				(width 0.1524)
				(type default)
			)
			(layer "F.SilkS")
		)
		(fp_line
			(start -0.12065 -0.305054)
			(end -0.12065 -0.2794)
			(stroke
				(width 0.1)
				(type default)
			)
			(layer "F.Fab")
		)
		(fp_line
			(start -0.67945 -0.305054)
			(end -0.12065 -0.305054)
			(stroke
				(width 0.1)
				(type default)
			)
			(layer "F.Fab")
		)
		(fp_line
			(start 0.67945 -0.3048)
			(end 0.67945 0.3048)
			(stroke
				(width 0.1)
				(type default)
			)
			(layer "F.Fab")
		)
		(fp_line
			(start 0.12065 -0.3048)
			(end 0.67945 -0.3048)
			(stroke
				(width 0.1)
				(type default)
			)
			(layer "F.Fab")
		)
		(fp_line
			(start 0.12065 -0.2794)
			(end 0.12065 -0.3048)
			(stroke
				(width 0.1)
				(type default)
			)
			(layer "F.Fab")
		)
		(fp_line
			(start -0.12065 -0.2794)
			(end 0.12065 -0.2794)
			(stroke
				(width 0.1)
				(type default)
			)
			(layer "F.Fab")
		)
		(fp_line
			(start 0.120396 0.2794)
			(end -0.12065 0.2794)
			(stroke
				(width 0.1)
				(type default)
			)
			(layer "F.Fab")
		)
		(fp_line
			(start -0.12065 0.2794)
			(end -0.12065 0.3048)
			(stroke
				(width 0.1)
				(type default)
			)
			(layer "F.Fab")
		)
		(fp_line
			(start 0.67945 0.3048)
			(end 0.120396 0.3048)
			(stroke
				(width 0.1)
				(type default)
			)
			(layer "F.Fab")
		)
		(fp_line
			(start 0.120396 0.3048)
			(end 0.120396 0.2794)
			(stroke
				(width 0.1)
				(type default)
			)
			(layer "F.Fab")
		)
		(fp_line
			(start -0.12065 0.3048)
			(end -0.67945 0.3048)
			(stroke
				(width 0.1)
				(type default)
			)
			(layer "F.Fab")
		)
		(fp_line
			(start -0.67945 0.3048)
			(end -0.67945 -0.305054)
			(stroke
				(width 0.1)
				(type default)
			)
			(layer "F.Fab")
		)
		(pad "1" smd circle
			(at -0.40005 0 90)
			(size 0 0)
			(layers "F.Cu" "F.Mask" "F.Paste")
			(net "PVCCIN_CPU0")
		)
		(pad "2" smd circle
			(at 0.40005 0 90)
			(size 0 0)
			(layers "F.Cu" "F.Mask" "F.Paste")
			(net "GND")
		)
	)
	(footprint ""
		(layer "F.Cu")
		(at 386.71373 -402.371052 -90)
		(property "Reference" "C945"
			(at 0 0 270)
			(layer "F.SilkS")
			(hide yes)
			(effects
				(font
					(size 1.27 1.27)
				)
			)
		)
		(property "Value" ""
			(at 0 0 270)
			(layer "F.Fab")
			(effects
				(font
					(size 1.27 1.27)
				)
			)
		)
		(duplicate_pad_numbers_are_jumpers no)
		(fp_line
			(start -0.299974 0.150114)
			(end -0.299974 -0.150114)
			(stroke
				(width 0.1)
				(type default)
			)
			(layer "F.Fab")
		)
		(fp_line
			(start 0.299974 0.150114)
			(end -0.299974 0.150114)
			(stroke
				(width 0.1)
				(type default)
			)
			(layer "F.Fab")
		)
		(fp_line
			(start -0.299974 -0.150114)
			(end 0.299974 -0.150114)
			(stroke
				(width 0.1)
				(type default)
			)
			(layer "F.Fab")
		)
		(fp_line
			(start 0.299974 -0.150114)
			(end 0.299974 0.150114)
			(stroke
				(width 0.1)
				(type default)
			)
			(layer "F.Fab")
		)
		(pad "1" smd rect
			(at -0.2667 0 270)
			(size 0.3048 0.381)
			(layers "F.Cu" "F.Mask" "F.Paste")
			(net "P5E_CPU0_PE2_TX_C_DP<10>")
		)
		(pad "2" smd rect
			(at 0.2667 0 270)
			(size 0.3048 0.381)
			(layers "F.Cu" "F.Mask" "F.Paste")
			(net "P5E_CPU0_PE2_TX_DP<10>")
		)
	)
)
